# S9S_MB_2U (Grand Teton) — schematic netlist excerpt (pin names and nets, part order shuffled) for the footprints in the layout excerpt that follows; sources: Cadence DE-HDL packaged netlist, KiCad conversion of 03242023_DA0F0TMBIJ0_F0T_Motherboard_J_brd_V01_OCP.brd

R295  Q_RES  240 1% EMPTY  pkg 0402LF  page 119 : A = GND ; B = PD_CPU0_ENH_MCECC_DIS
C2319  Q_CAP  0.1UF 25V 10% EMPTY  pkg 0402  page 196 : A = P3V3_AUX_USB_HUB_2 ; B = GND

(kicad_pcb
	(version 20260206)
	(generator "pcbnew")
	(generator_version "10.0")
	(general
		(thickness 1.6)
		(legacy_teardrops no)
	)
	(paper "A4")
	(title_block
		(title "03242023_DA0F0TMBIJ0_F0T_Motherboard_J_brd_V01_OCP.brd")
		(comment 1 "Grand Teton / footprints 4467-4469 of 6105")
	)
	(layers
		(0 "F.Cu" signal "TOP")
		(4 "In1.Cu" signal "GND")
		(6 "In2.Cu" signal "IN1")
		(8 "In3.Cu" signal "GND1")
		(10 "In4.Cu" signal "IN2")
		(12 "In5.Cu" signal "GND2")
		(14 "In6.Cu" signal "IN3")
		(16 "In7.Cu" signal "GND3")
		(18 "In8.Cu" signal "VCC")
		(20 "In9.Cu" signal "VCC1")
		(22 "In10.Cu" signal "GND4")
		(24 "In11.Cu" signal "IN4")
		(26 "In12.Cu" signal "GND5")
		(28 "In13.Cu" signal "IN5")
		(30 "In14.Cu" signal "GND6")
		(32 "In15.Cu" signal "IN6")
		(34 "In16.Cu" signal "GND7")
		(2 "B.Cu" signal "BOTTOM")
		(9 "F.Adhes" user "F.Adhesive")
		(11 "B.Adhes" user "B.Adhesive")
		(13 "F.Paste" user "Package Geometry/Pastemask Top")
		(15 "B.Paste" user "Package Geometry/Pastemask Bottom")
		(5 "F.SilkS" user "Ref Des/Silkscreen Top")
		(7 "B.SilkS" user "Ref Des/Silkscreen Bottom")
		(1 "F.Mask" user "Board Geometry/Soldermask Top")
		(3 "B.Mask" user "Board Geometry/Soldermask Bottom")
		(17 "Dwgs.User" user "User.Drawings")
		(19 "Cmts.User" user "User.Comments")
		(21 "Eco1.User" user "User.Eco1")
		(23 "Eco2.User" user "User.Eco2")
		(25 "Edge.Cuts" user "Board Geometry/Outline")
		(27 "Margin" user)
		(31 "F.CrtYd" user "Package Geometry/Place Bound Top")
		(29 "B.CrtYd" user "Package Geometry/Place Bound Bottom")
		(35 "F.Fab" user "Ref Des/Assembly Top")
		(33 "B.Fab" user "Ref Des/Assembly Bottom")
	)
	(footprint ""
		(layer "B.Cu")
		(at 157.686756 -39.871904 90)
		(property "Reference" "C2319"
			(at 0 0 90)
			(layer "B.SilkS")
			(hide yes)
			(effects
				(font
					(size 1.27 1.27)
				)
				(justify mirror)
			)
		)
		(property "Value" ""
			(at 0 0 90)
			(layer "B.Fab")
			(effects
				(font
					(size 1.27 1.27)
				)
				(justify mirror)
			)
		)
		(duplicate_pad_numbers_are_jumpers no)
		(fp_line
			(start 0.7874 -0.4064)
			(end -0.7874 -0.4064)
			(stroke
				(width 0.1524)
				(type default)
			)
			(layer "B.SilkS")
		)
		(fp_line
			(start -0.7874 -0.4064)
			(end -0.7874 0.4064)
			(stroke
				(width 0.1524)
				(type default)
			)
			(layer "B.SilkS")
		)
		(fp_line
			(start 0.7874 0.4064)
			(end 0.7874 -0.4064)
			(stroke
				(width 0.1524)
				(type default)
			)
			(layer "B.SilkS")
		)
		(fp_line
			(start -0.7874 0.4064)
			(end 0.7874 0.4064)
			(stroke
				(width 0.1524)
				(type default)
			)
			(layer "B.SilkS")
		)
		(fp_line
			(start 0.67945 -0.305054)
			(end 0.12065 -0.305054)
			(stroke
				(width 0.1)
				(type default)
			)
			(layer "B.Fab")
		)
		(fp_line
			(start 0.12065 -0.305054)
			(end 0.12065 -0.2794)
			(stroke
				(width 0.1)
				(type default)
			)
			(layer "B.Fab")
		)
		(fp_line
			(start -0.12065 -0.3048)
			(end -0.67945 -0.3048)
			(stroke
				(width 0.1)
				(type default)
			)
			(layer "B.Fab")
		)
		(fp_line
			(start -0.67945 -0.3048)
			(end -0.67945 0.3048)
			(stroke
				(width 0.1)
				(type default)
			)
			(layer "B.Fab")
		)
		(fp_line
			(start 0.12065 -0.2794)
			(end -0.12065 -0.2794)
			(stroke
				(width 0.1)
				(type default)
			)
			(layer "B.Fab")
		)
		(fp_line
			(start -0.12065 -0.2794)
			(end -0.12065 -0.3048)
			(stroke
				(width 0.1)
				(type default)
			)
			(layer "B.Fab")
		)
		(fp_line
			(start 0.12065 0.2794)
			(end 0.12065 0.3048)
			(stroke
				(width 0.1)
				(type default)
			)
			(layer "B.Fab")
		)
		(fp_line
			(start -0.120396 0.2794)
			(end 0.12065 0.2794)
			(stroke
				(width 0.1)
				(type default)
			)
			(layer "B.Fab")
		)
		(fp_line
			(start 0.67945 0.3048)
			(end 0.67945 -0.305054)
			(stroke
				(width 0.1)
				(type default)
			)
			(layer "B.Fab")
		)
		(fp_line
			(start 0.12065 0.3048)
			(end 0.67945 0.3048)
			(stroke
				(width 0.1)
				(type default)
			)
			(layer "B.Fab")
		)
		(fp_line
			(start -0.120396 0.3048)
			(end -0.120396 0.2794)
			(stroke
				(width 0.1)
				(type default)
			)
			(layer "B.Fab")
		)
		(fp_line
			(start -0.67945 0.3048)
			(end -0.120396 0.3048)
			(stroke
				(width 0.1)
				(type default)
			)
			(layer "B.Fab")
		)
		(pad "1" smd circle
			(at 0.40005 0 270)
			(size 0 0)
			(layers "B.Cu" "B.Mask" "B.Paste")
			(net "P3V3_AUX_USB_HUB_2")
		)
		(pad "2" smd circle
			(at -0.40005 0 270)
			(size 0 0)
			(layers "B.Cu" "B.Mask" "B.Paste")
			(net "GND")
		)
	)
	(footprint ""
		(layer "B.Cu")
		(at 375.578624 -190.703454 -90)
		(property "Reference" "R295"
			(at 0 0 90)
			(layer "B.SilkS")
			(hide yes)
			(effects
				(font
					(size 1.27 1.27)
				)
				(justify mirror)
			)
		)
		(property "Value" ""
			(at 0 0 90)
			(layer "B.Fab")
			(effects
				(font
					(size 1.27 1.27)
				)
				(justify mirror)
			)
		)
		(duplicate_pad_numbers_are_jumpers no)
		(fp_line
			(start -0.7874 0.4064)
			(end 0.7874 0.4064)
			(stroke
				(width 0.1524)
				(type default)
			)
			(layer "B.SilkS")
		)
		(fp_line
			(start 0.7874 0.4064)
			(end 0.7874 -0.4064)
			(stroke
				(width 0.1524)
				(type default)
			)
			(layer "B.SilkS")
		)
		(fp_line
			(start -0.7874 -0.4064)
			(end -0.7874 0.4064)
			(stroke
				(width 0.1524)
				(type default)
			)
			(layer "B.SilkS")
		)
		(fp_line
			(start 0.7874 -0.4064)
			(end -0.7874 -0.4064)
			(stroke
				(width 0.1524)
				(type default)
			)
			(layer "B.SilkS")
		)
		(fp_line
			(start -0.67945 0.3048)
			(end -0.120396 0.3048)
			(stroke
				(width 0.1)
				(type default)
			)
			(layer "B.Fab")
		)
		(fp_line
			(start -0.120396 0.3048)
			(end -0.120396 0.2794)
			(stroke
				(width 0.1)
				(type default)
			)
			(layer "B.Fab")
		)
		(fp_line
			(start 0.12065 0.3048)
			(end 0.67945 0.3048)
			(stroke
				(width 0.1)
				(type default)
			)
			(layer "B.Fab")
		)
		(fp_line
			(start 0.67945 0.3048)
			(end 0.67945 -0.305054)
			(stroke
				(width 0.1)
				(type default)
			)
			(layer "B.Fab")
		)
		(fp_line
			(start -0.120396 0.2794)
			(end 0.12065 0.2794)
			(stroke
				(width 0.1)
				(type default)
			)
			(layer "B.Fab")
		)
		(fp_line
			(start 0.12065 0.2794)
			(end 0.12065 0.3048)
			(stroke
				(width 0.1)
				(type default)
			)
			(layer "B.Fab")
		)
		(fp_line
			(start -0.12065 -0.2794)
			(end -0.12065 -0.3048)
			(stroke
				(width 0.1)
				(type default)
			)
			(layer "B.Fab")
		)
		(fp_line
			(start 0.12065 -0.2794)
			(end -0.12065 -0.2794)
			(stroke
				(width 0.1)
				(type default)
			)
			(layer "B.Fab")
		)
		(fp_line
			(start -0.67945 -0.3048)
			(end -0.67945 0.3048)
			(stroke
				(width 0.1)
				(type default)
			)
			(layer "B.Fab")
		)
		(fp_line
			(start -0.12065 -0.3048)
			(end -0.67945 -0.3048)
			(stroke
				(width 0.1)
				(type default)
			)
			(layer "B.Fab")
		)
		(fp_line
			(start 0.12065 -0.305054)
			(end 0.12065 -0.2794)
			(stroke
				(width 0.1)
				(type default)
			)
			(layer "B.Fab")
		)
		(fp_line
			(start 0.67945 -0.305054)
			(end 0.12065 -0.305054)
			(stroke
				(width 0.1)
				(type default)
			)
			(layer "B.Fab")
		)
		(pad "1" smd circle
			(at 0.40005 0 90)
			(size 0 0)
			(layers "B.Cu" "B.Mask" "B.Paste")
			(net "GND")
		)
		(pad "2" smd circle
			(at -0.40005 0 90)
			(size 0 0)
			(layers "B.Cu" "B.Mask" "B.Paste")
			(net "PD_CPU0_ENH_MCECC_DIS")
		)
	)
	(footprint ""
		(layer "B.Cu")
		(at 8.22198 -37.551868)
		(property "Reference" ""
			(at 0 0 0)
			(layer "B.SilkS")
			(hide yes)
			(effects
				(font
					(size 1.27 1.27)
				)
				(justify mirror)
			)
		)
		(property "Value" ""
			(at 0 0 0)
			(layer "B.Fab")
			(effects
				(font
					(size 1.27 1.27)
				)
				(justify mirror)
			)
		)
		(duplicate_pad_numbers_are_jumpers no)
		(pad "1" smd circle
			(at 0 0 180)
			(size 0.9906 0.9906)
			(layers "B.Cu" "B.Mask" "B.Paste")
			(net "Net_291")
		)
		(zone
			(layer "B.Cu")
			(hatch none 0.5)
			(connect_pads
				(clearance 0)
			)
			(min_thickness 0.25)
			(keepout
				(tracks not_allowed)
				(vias allowed)
				(pads allowed)
				(copperpour not_allowed)
				(footprints allowed)
			)
			(placement
				(enabled no)
				(sheetname "")
			)
			(fill
				(thermal_gap 0.5)
				(thermal_bridge_width 0.5)
				(island_removal_mode 0)
			)
			(polygon
				(pts
					(arc
						(start 9.84758 -37.551868)
						(mid 6.59638 -37.551868)
						(end 9.84758 -37.551868)
					)
				)
			)
		)
	)
)
